(kicad_pcb
	(version 20260206)
	(generator "pcbnew")
	(generator_version "10.0")
	(general
		(thickness 1.6)
		(legacy_teardrops no)
	)
	(paper "A4")
	(title_block
		(title "baseboard — 13948-1b.1110WZS1818.brd")
		(comment 1 "Honey Badger (Wiwynn) / footprints 1570-1576 of 2523")
	)
	(layers
		(0 "F.Cu" signal "TOP")
		(4 "In1.Cu" signal "L2GND")
		(6 "In2.Cu" signal "L3")
		(8 "In3.Cu" signal "L4VCC")
		(10 "In4.Cu" signal "L5VCC")
		(12 "In5.Cu" signal "L6")
		(14 "In6.Cu" signal "L7GND")
		(2 "B.Cu" signal "BOTTOM")
		(9 "F.Adhes" user "F.Adhesive")
		(11 "B.Adhes" user "B.Adhesive")
		(13 "F.Paste" user "Package Geometry/Pastemask Top")
		(15 "B.Paste" user "Package Geometry/Pastemask Bottom")
		(5 "F.SilkS" user "Ref Des/Silkscreen Top")
		(7 "B.SilkS" user "Ref Des/Silkscreen Bottom")
		(1 "F.Mask" user "Board Geometry/Soldermask Top")
		(3 "B.Mask" user "Board Geometry/Soldermask Bottom")
		(17 "Dwgs.User" user "User.Drawings")
		(19 "Cmts.User" user "User.Comments")
		(21 "Eco1.User" user "User.Eco1")
		(23 "Eco2.User" user "User.Eco2")
		(25 "Edge.Cuts" user "Board Geometry/Outline")
		(27 "Margin" user)
		(31 "F.CrtYd" user "Package Geometry/Place Bound Top")
		(29 "B.CrtYd" user "Package Geometry/Place Bound Bottom")
		(35 "F.Fab" user "Ref Des/Assembly Top")
		(33 "B.Fab" user "Ref Des/Assembly Bottom")
	)
	(footprint ""
		(layer "F.Cu")
		(at 211.72297 -69.088)
		(property "Reference" "R13"
			(at 0 0 0)
			(layer "F.SilkS")
			(hide yes)
			(effects
				(font
					(size 1.27 1.27)
				)
			)
		)
		(property "Value" "10KR2F-2-GP"
			(at 0.064008 -3.993896 0)
			(unlocked yes)
			(layer "F.Fab")
			(hide yes)
			(effects
				(font
					(size 1.016 1.016)
					(thickness 0.1524)
				)
			)
		)
		(property "Device Type" "R402H16"
			(at 0.064008 -5.517896 0)
			(unlocked yes)
			(layer "F.Fab")
			(hide yes)
			(effects
				(font
					(size 1.016 1.016)
					(thickness 0.1524)
				)
			)
		)
		(duplicate_pad_numbers_are_jumpers no)
		(fp_line
			(start -0.508 -0.9398)
			(end -0.508 0.9398)
			(stroke
				(width 0.1524)
				(type default)
			)
			(layer "F.SilkS")
		)
		(fp_line
			(start 0.508 -0.9398)
			(end -0.508 -0.9398)
			(stroke
				(width 0.1524)
				(type default)
			)
			(layer "F.SilkS")
		)
		(fp_rect
			(start -0.508 0.9398)
			(end 0.508 -0.9398)
			(stroke
				(width 0)
				(type default)
			)
			(fill no)
			(layer "F.CrtYd")
		)
		(fp_rect
			(start -0.508 0.9398)
			(end 0.508 -0.9398)
			(stroke
				(width 0)
				(type default)
			)
			(fill no)
			(layer "F.Fab")
		)
		(pad "1" smd custom
			(at 0 -0.4445)
			(size 0.1397 0.1397)
			(layers "F.Cu" "F.Mask" "F.Paste")
			(net "SVR_ID2")
			(options
				(clearance outline)
				(anchor circle)
			)
			(primitives
				(gr_poly
					(pts
						(arc
							(start -0.1778 -0.2794)
							(mid -0.249642 -0.249642)
							(end -0.2794 -0.1778)
						)
						(arc
							(start -0.2794 0.1778)
							(mid -0.249642 0.249642)
							(end -0.1778 0.2794)
						)
						(arc
							(start 0.1778 0.2794)
							(mid 0.249642 0.249642)
							(end 0.2794 0.1778)
						)
						(arc
							(start 0.2794 -0.1778)
							(mid 0.249642 -0.249642)
							(end 0.1778 -0.2794)
						)
					)
					(width 0)
					(fill yes)
				)
			)
		)
		(pad "2" smd custom
			(at 0 0.4445)
			(size 0.1397 0.1397)
			(layers "F.Cu" "F.Mask" "F.Paste")
			(net "P3V3_STBY")
			(options
				(clearance outline)
				(anchor circle)
			)
			(primitives
				(gr_poly
					(pts
						(arc
							(start -0.1778 -0.2794)
							(mid -0.249642 -0.249642)
							(end -0.2794 -0.1778)
						)
						(arc
							(start -0.2794 0.1778)
							(mid -0.249642 0.249642)
							(end -0.1778 0.2794)
						)
						(arc
							(start 0.1778 0.2794)
							(mid 0.249642 0.249642)
							(end 0.2794 0.1778)
						)
						(arc
							(start 0.2794 -0.1778)
							(mid 0.249642 -0.249642)
							(end 0.1778 -0.2794)
						)
					)
					(width 0)
					(fill yes)
				)
			)
		)
	)
	(footprint ""
		(layer "F.Cu")
		(at 283.21 -161.544)
		(property "Reference" "R259"
			(at 0 0 0)
			(layer "F.SilkS")
			(hide yes)
			(effects
				(font
					(size 1.27 1.27)
				)
			)
		)
		(property "Value" "100KR2F-L1-GP"
			(at 0.064008 -3.993896 0)
			(unlocked yes)
			(layer "F.Fab")
			(hide yes)
			(effects
				(font
					(size 1.016 1.016)
					(thickness 0.1524)
				)
			)
		)
		(property "Device Type" "R402H16"
			(at 0.064008 -5.517896 0)
			(unlocked yes)
			(layer "F.Fab")
			(hide yes)
			(effects
				(font
					(size 1.016 1.016)
					(thickness 0.1524)
				)
			)
		)
		(duplicate_pad_numbers_are_jumpers no)
		(fp_line
			(start -0.508 -0.9398)
			(end -0.508 0.9398)
			(stroke
				(width 0.1524)
				(type default)
			)
			(layer "F.SilkS")
		)
		(fp_line
			(start 0.508 -0.9398)
			(end -0.508 -0.9398)
			(stroke
				(width 0.1524)
				(type default)
			)
			(layer "F.SilkS")
		)
		(fp_rect
			(start -0.508 0.9398)
			(end 0.508 -0.9398)
			(stroke
				(width 0)
				(type default)
			)
			(fill no)
			(layer "F.CrtYd")
		)
		(fp_rect
			(start -0.508 0.9398)
			(end 0.508 -0.9398)
			(stroke
				(width 0)
				(type default)
			)
			(fill no)
			(layer "F.Fab")
		)
		(pad "1" smd custom
			(at 0 -0.4445)
			(size 0.1397 0.1397)
			(layers "F.Cu" "F.Mask" "F.Paste")
			(net "TP_IRQ_CPU_SERIAL")
			(options
				(clearance outline)
				(anchor circle)
			)
			(primitives
				(gr_poly
					(pts
						(arc
							(start -0.1778 -0.2794)
							(mid -0.249642 -0.249642)
							(end -0.2794 -0.1778)
						)
						(arc
							(start -0.2794 0.1778)
							(mid -0.249642 0.249642)
							(end -0.1778 0.2794)
						)
						(arc
							(start 0.1778 0.2794)
							(mid 0.249642 0.249642)
							(end 0.2794 0.1778)
						)
						(arc
							(start 0.2794 -0.1778)
							(mid 0.249642 -0.249642)
							(end 0.1778 -0.2794)
						)
					)
					(width 0)
					(fill yes)
				)
			)
		)
		(pad "2" smd custom
			(at 0 0.4445)
			(size 0.1397 0.1397)
			(layers "F.Cu" "F.Mask" "F.Paste")
			(net "GND")
			(options
				(clearance outline)
				(anchor circle)
			)
			(primitives
				(gr_poly
					(pts
						(arc
							(start -0.1778 -0.2794)
							(mid -0.249642 -0.249642)
							(end -0.2794 -0.1778)
						)
						(arc
							(start -0.2794 0.1778)
							(mid -0.249642 0.249642)
							(end -0.1778 0.2794)
						)
						(arc
							(start 0.1778 0.2794)
							(mid 0.249642 0.249642)
							(end 0.2794 0.1778)
						)
						(arc
							(start 0.2794 -0.1778)
							(mid 0.249642 -0.249642)
							(end 0.1778 -0.2794)
						)
					)
					(width 0)
					(fill yes)
				)
			)
		)
	)
	(footprint ""
		(layer "F.Cu")
		(at 301.752 -191.897 180)
		(property "Reference" "C319"
			(at 0 0 180)
			(layer "F.SilkS")
			(hide yes)
			(effects
				(font
					(size 1.27 1.27)
				)
			)
		)
		(property "Value" "SCD1U16V2KX-3GP"
			(at 1.1811 -2.7051 180)
			(unlocked yes)
			(layer "F.Fab")
			(hide yes)
			(effects
				(font
					(size 1.016 1.016)
					(thickness 0.1524)
				)
			)
		)
		(property "Device Type" "C402H22"
			(at 1.1811 -4.2291 180)
			(unlocked yes)
			(layer "F.Fab")
			(hide yes)
			(effects
				(font
					(size 1.016 1.016)
					(thickness 0.1524)
				)
			)
		)
		(duplicate_pad_numbers_are_jumpers no)
		(fp_rect
			(start -0.4318 0.9525)
			(end 0.4318 -0.9525)
			(stroke
				(width 0)
				(type default)
			)
			(fill no)
			(layer "F.CrtYd")
		)
		(fp_rect
			(start -0.4318 0.9525)
			(end 0.4318 -0.9525)
			(stroke
				(width 0)
				(type default)
			)
			(fill no)
			(layer "F.Fab")
		)
		(pad "1" smd custom
			(at 0 -0.4445 180)
			(size 0.1524 0.1524)
			(layers "F.Cu" "F.Mask" "F.Paste")
			(net "UART COUNT")
			(options
				(clearance outline)
				(anchor circle)
			)
			(primitives
				(gr_poly
					(pts
						(arc
							(start 0.3048 -0.2032)
							(mid 0.275042 -0.275042)
							(end 0.2032 -0.3048)
						)
						(arc
							(start -0.2032 -0.3048)
							(mid -0.275042 -0.275042)
							(end -0.3048 -0.2032)
						)
						(arc
							(start -0.3048 0.2032)
							(mid -0.275042 0.275042)
							(end -0.2032 0.3048)
						)
						(arc
							(start 0.2032 0.3048)
							(mid 0.275042 0.275042)
							(end 0.3048 0.2032)
						)
					)
					(width 0)
					(fill yes)
				)
			)
		)
		(pad "2" smd custom
			(at 0 0.4445 180)
			(size 0.1524 0.1524)
			(layers "F.Cu" "F.Mask" "F.Paste")
			(net "GND")
			(options
				(clearance outline)
				(anchor circle)
			)
			(primitives
				(gr_poly
					(pts
						(arc
							(start 0.3048 -0.2032)
							(mid 0.275042 -0.275042)
							(end 0.2032 -0.3048)
						)
						(arc
							(start -0.2032 -0.3048)
							(mid -0.275042 -0.275042)
							(end -0.3048 -0.2032)
						)
						(arc
							(start -0.3048 0.2032)
							(mid -0.275042 0.275042)
							(end -0.2032 0.3048)
						)
						(arc
							(start 0.2032 0.3048)
							(mid 0.275042 0.275042)
							(end 0.3048 0.2032)
						)
					)
					(width 0)
					(fill yes)
				)
			)
		)
	)
	(footprint ""
		(layer "F.Cu")
		(at 120.339612 -222.885)
		(property "Reference" "SR874"
			(at 0 0 0)
			(layer "F.SilkS")
			(hide yes)
			(effects
				(font
					(size 1.27 1.27)
				)
			)
		)
		(property "Value" "0R2J-2-GP"
			(at 0.064008 -3.993896 0)
			(unlocked yes)
			(layer "F.Fab")
			(hide yes)
			(effects
				(font
					(size 1.016 1.016)
					(thickness 0.1524)
				)
			)
		)
		(property "Device Type" "R402H16"
			(at 0.064008 -5.517896 0)
			(unlocked yes)
			(layer "F.Fab")
			(hide yes)
			(effects
				(font
					(size 1.016 1.016)
					(thickness 0.1524)
				)
			)
		)
		(duplicate_pad_numbers_are_jumpers no)
		(fp_line
			(start -0.508 -0.9398)
			(end -0.508 0.9398)
			(stroke
				(width 0.1524)
				(type default)
			)
			(layer "F.SilkS")
		)
		(fp_line
			(start 0.508 -0.9398)
			(end -0.508 -0.9398)
			(stroke
				(width 0.1524)
				(type default)
			)
			(layer "F.SilkS")
		)
		(fp_rect
			(start -0.508 0.9398)
			(end 0.508 -0.9398)
			(stroke
				(width 0)
				(type default)
			)
			(fill no)
			(layer "F.CrtYd")
		)
		(fp_rect
			(start -0.508 0.9398)
			(end 0.508 -0.9398)
			(stroke
				(width 0)
				(type default)
			)
			(fill no)
			(layer "F.Fab")
		)
		(pad "1" smd custom
			(at 0 -0.4445)
			(size 0.1397 0.1397)
			(layers "F.Cu" "F.Mask" "F.Paste")
			(net "SAS_HDD_CONN_SER_TX7_N")
			(options
				(clearance outline)
				(anchor circle)
			)
			(primitives
				(gr_poly
					(pts
						(arc
							(start -0.1778 -0.2794)
							(mid -0.249642 -0.249642)
							(end -0.2794 -0.1778)
						)
						(arc
							(start -0.2794 0.1778)
							(mid -0.249642 0.249642)
							(end -0.1778 0.2794)
						)
						(arc
							(start 0.1778 0.2794)
							(mid 0.249642 0.249642)
							(end 0.2794 0.1778)
						)
						(arc
							(start 0.2794 -0.1778)
							(mid 0.249642 -0.249642)
							(end 0.1778 -0.2794)
						)
					)
					(width 0)
					(fill yes)
				)
			)
		)
		(pad "2" smd custom
			(at 0 0.4445)
			(size 0.1397 0.1397)
			(layers "F.Cu" "F.Mask" "F.Paste")
			(net "SAS_HDD_CONN_TX7_N")
			(options
				(clearance outline)
				(anchor circle)
			)
			(primitives
				(gr_poly
					(pts
						(arc
							(start -0.1778 -0.2794)
							(mid -0.249642 -0.249642)
							(end -0.2794 -0.1778)
						)
						(arc
							(start -0.2794 0.1778)
							(mid -0.249642 0.249642)
							(end -0.1778 0.2794)
						)
						(arc
							(start 0.1778 0.2794)
							(mid 0.249642 0.249642)
							(end 0.2794 0.1778)
						)
						(arc
							(start 0.2794 -0.1778)
							(mid 0.249642 -0.249642)
							(end 0.1778 -0.2794)
						)
					)
					(width 0)
					(fill yes)
				)
			)
		)
	)
	(footprint ""
		(layer "F.Cu")
		(at 95.70847 -103.759 -90)
		(property "Reference" "SR790"
			(at 0 0 270)
			(layer "F.SilkS")
			(hide yes)
			(effects
				(font
					(size 1.27 1.27)
				)
			)
		)
		(property "Value" "0R2J-2-GP"
			(at 0.064008 -3.993896 270)
			(unlocked yes)
			(layer "F.Fab")
			(hide yes)
			(effects
				(font
					(size 1.016 1.016)
					(thickness 0.1524)
				)
			)
		)
		(property "Device Type" "R402H16"
			(at 0.064008 -5.517896 270)
			(unlocked yes)
			(layer "F.Fab")
			(hide yes)
			(effects
				(font
					(size 1.016 1.016)
					(thickness 0.1524)
				)
			)
		)
		(duplicate_pad_numbers_are_jumpers no)
		(fp_line
			(start -0.508 -0.9398)
			(end -0.508 0.9398)
			(stroke
				(width 0.1524)
				(type default)
			)
			(layer "F.SilkS")
		)
		(fp_line
			(start 0.508 -0.9398)
			(end -0.508 -0.9398)
			(stroke
				(width 0.1524)
				(type default)
			)
			(layer "F.SilkS")
		)
		(fp_rect
			(start -0.508 0.9398)
			(end 0.508 -0.9398)
			(stroke
				(width 0)
				(type default)
			)
			(fill no)
			(layer "F.CrtYd")
		)
		(fp_rect
			(start -0.508 0.9398)
			(end 0.508 -0.9398)
			(stroke
				(width 0)
				(type default)
			)
			(fill no)
			(layer "F.Fab")
		)
		(pad "1" smd custom
			(at 0 -0.4445 270)
			(size 0.1397 0.1397)
			(layers "F.Cu" "F.Mask" "F.Paste")
			(net "SDB_R_TX")
			(options
				(clearance outline)
				(anchor circle)
			)
			(primitives
				(gr_poly
					(pts
						(arc
							(start -0.1778 -0.2794)
							(mid -0.249642 -0.249642)
							(end -0.2794 -0.1778)
						)
						(arc
							(start -0.2794 0.1778)
							(mid -0.249642 0.249642)
							(end -0.1778 0.2794)
						)
						(arc
							(start 0.1778 0.2794)
							(mid 0.249642 0.249642)
							(end 0.2794 0.1778)
						)
						(arc
							(start 0.2794 -0.1778)
							(mid 0.249642 -0.249642)
							(end 0.1778 -0.2794)
						)
					)
					(width 0)
					(fill yes)
				)
			)
		)
		(pad "2" smd custom
			(at 0 0.4445 270)
			(size 0.1397 0.1397)
			(layers "F.Cu" "F.Mask" "F.Paste")
			(net "SDB_TX")
			(options
				(clearance outline)
				(anchor circle)
			)
			(primitives
				(gr_poly
					(pts
						(arc
							(start -0.1778 -0.2794)
							(mid -0.249642 -0.249642)
							(end -0.2794 -0.1778)
						)
						(arc
							(start -0.2794 0.1778)
							(mid -0.249642 0.249642)
							(end -0.1778 0.2794)
						)
						(arc
							(start 0.1778 0.2794)
							(mid 0.249642 0.249642)
							(end 0.2794 0.1778)
						)
						(arc
							(start 0.2794 -0.1778)
							(mid 0.249642 -0.249642)
							(end 0.1778 -0.2794)
						)
					)
					(width 0)
					(fill yes)
				)
			)
		)
	)
	(footprint ""
		(layer "F.Cu")
		(at 171.831 -195.199 90)
		(property "Reference" "R153"
			(at 0 0 90)
			(layer "F.SilkS")
			(hide yes)
			(effects
				(font
					(size 1.27 1.27)
				)
			)
		)
		(property "Value" "0R2J-2-GP"
			(at 0.064008 -3.993896 90)
			(unlocked yes)
			(layer "F.Fab")
			(hide yes)
			(effects
				(font
					(size 1.016 1.016)
					(thickness 0.1524)
				)
			)
		)
		(property "Device Type" "R402H16"
			(at 0.064008 -5.517896 90)
			(unlocked yes)
			(layer "F.Fab")
			(hide yes)
			(effects
				(font
					(size 1.016 1.016)
					(thickness 0.1524)
				)
			)
		)
		(duplicate_pad_numbers_are_jumpers no)
		(fp_line
			(start 0.508 -0.9398)
			(end -0.508 -0.9398)
			(stroke
				(width 0.1524)
				(type default)
			)
			(layer "F.SilkS")
		)
		(fp_line
			(start -0.508 -0.9398)
			(end -0.508 0.9398)
			(stroke
				(width 0.1524)
				(type default)
			)
			(layer "F.SilkS")
		)
		(fp_rect
			(start -0.508 0.9398)
			(end 0.508 -0.9398)
			(stroke
				(width 0)
				(type default)
			)
			(fill no)
			(layer "F.CrtYd")
		)
		(fp_rect
			(start -0.508 0.9398)
			(end 0.508 -0.9398)
			(stroke
				(width 0)
				(type default)
			)
			(fill no)
			(layer "F.Fab")
		)
		(pad "1" smd custom
			(at 0 -0.4445 90)
			(size 0.1397 0.1397)
			(layers "F.Cu" "F.Mask" "F.Paste")
			(net "SAS_I2C_C_BUF_SCL_R")
			(options
				(clearance outline)
				(anchor circle)
			)
			(primitives
				(gr_poly
					(pts
						(arc
							(start -0.1778 -0.2794)
							(mid -0.249642 -0.249642)
							(end -0.2794 -0.1778)
						)
						(arc
							(start -0.2794 0.1778)
							(mid -0.249642 0.249642)
							(end -0.1778 0.2794)
						)
						(arc
							(start 0.1778 0.2794)
							(mid 0.249642 0.249642)
							(end 0.2794 0.1778)
						)
						(arc
							(start 0.2794 -0.1778)
							(mid 0.249642 -0.249642)
							(end 0.1778 -0.2794)
						)
					)
					(width 0)
					(fill yes)
				)
			)
		)
		(pad "2" smd custom
			(at 0 0.4445 90)
			(size 0.1397 0.1397)
			(layers "F.Cu" "F.Mask" "F.Paste")
			(net "SAS_I2C_C_BUF_SCL")
			(options
				(clearance outline)
				(anchor circle)
			)
			(primitives
				(gr_poly
					(pts
						(arc
							(start -0.1778 -0.2794)
							(mid -0.249642 -0.249642)
							(end -0.2794 -0.1778)
						)
						(arc
							(start -0.2794 0.1778)
							(mid -0.249642 0.249642)
							(end -0.1778 0.2794)
						)
						(arc
							(start 0.1778 0.2794)
							(mid 0.249642 0.249642)
							(end 0.2794 0.1778)
						)
						(arc
							(start 0.2794 -0.1778)
							(mid 0.249642 -0.249642)
							(end 0.1778 -0.2794)
						)
					)
					(width 0)
					(fill yes)
				)
			)
		)
	)
	(footprint ""
		(layer "F.Cu")
		(at 185.855864 -38.172136)
		(property "Reference" "R371"
			(at 0 0 0)
			(layer "F.SilkS")
			(hide yes)
			(effects
				(font
					(size 1.27 1.27)
				)
			)
		)
		(property "Value" "10KR2F-2-GP"
			(at 0.064008 -3.993896 0)
			(unlocked yes)
			(layer "F.Fab")
			(hide yes)
			(effects
				(font
					(size 1.016 1.016)
					(thickness 0.1524)
				)
			)
		)
		(property "Device Type" "R402H16"
			(at 0.064008 -5.517896 0)
			(unlocked yes)
			(layer "F.Fab")
			(hide yes)
			(effects
				(font
					(size 1.016 1.016)
					(thickness 0.1524)
				)
			)
		)
		(duplicate_pad_numbers_are_jumpers no)
		(fp_line
			(start -0.508 -0.9398)
			(end -0.508 0.9398)
			(stroke
				(width 0.1524)
				(type default)
			)
			(layer "F.SilkS")
		)
		(fp_line
			(start 0.508 -0.9398)
			(end -0.508 -0.9398)
			(stroke
				(width 0.1524)
				(type default)
			)
			(layer "F.SilkS")
		)
		(fp_rect
			(start -0.508 0.9398)
			(end 0.508 -0.9398)
			(stroke
				(width 0)
				(type default)
			)
			(fill no)
			(layer "F.CrtYd")
		)
		(fp_rect
			(start -0.508 0.9398)
			(end 0.508 -0.9398)
			(stroke
				(width 0)
				(type default)
			)
			(fill no)
			(layer "F.Fab")
		)
		(pad "1" smd custom
			(at 0 -0.4445)
			(size 0.1397 0.1397)
			(layers "F.Cu" "F.Mask" "F.Paste")
			(net "P3V3_STBY")
			(options
				(clearance outline)
				(anchor circle)
			)
			(primitives
				(gr_poly
					(pts
						(arc
							(start -0.1778 -0.2794)
							(mid -0.249642 -0.249642)
							(end -0.2794 -0.1778)
						)
						(arc
							(start -0.2794 0.1778)
							(mid -0.249642 0.249642)
							(end -0.1778 0.2794)
						)
						(arc
							(start 0.1778 0.2794)
							(mid 0.249642 0.249642)
							(end 0.2794 0.1778)
						)
						(arc
							(start 0.2794 -0.1778)
							(mid 0.249642 -0.249642)
							(end 0.1778 -0.2794)
						)
					)
					(width 0)
					(fill yes)
				)
			)
		)
		(pad "2" smd custom
			(at 0 0.4445)
			(size 0.1397 0.1397)
			(layers "F.Cu" "F.Mask" "F.Paste")
			(net "PHY_RESET#")
			(options
				(clearance outline)
				(anchor circle)
			)
			(primitives
				(gr_poly
					(pts
						(arc
							(start -0.1778 -0.2794)
							(mid -0.249642 -0.249642)
							(end -0.2794 -0.1778)
						)
						(arc
							(start -0.2794 0.1778)
							(mid -0.249642 0.249642)
							(end -0.1778 0.2794)
						)
						(arc
							(start 0.1778 0.2794)
							(mid 0.249642 0.249642)
							(end 0.2794 0.1778)
						)
						(arc
							(start 0.2794 -0.1778)
							(mid 0.249642 -0.249642)
							(end 0.1778 -0.2794)
						)
					)
					(width 0)
					(fill yes)
				)
			)
		)
	)
)
